(kicad_pcb
	(version 20260206)
	(generator "pcbnew")
	(generator_version "10.0")
	(general
		(thickness 1.6)
		(legacy_teardrops no)
	)
	(paper "A4")
	(title_block
		(title "Wiwynn_Tioga_Pass_MB.brd")
		(comment 1 "Tioga Pass / footprints 1689-1694 of 4770")
	)
	(layers
		(0 "F.Cu" signal "TOP")
		(4 "In1.Cu" signal "L2GND")
		(6 "In2.Cu" signal "L3")
		(8 "In3.Cu" signal "L4GND")
		(10 "In4.Cu" signal "L5")
		(12 "In5.Cu" signal "L6GND")
		(14 "In6.Cu" signal "L7VCC")
		(16 "In7.Cu" signal "L8VCC")
		(18 "In8.Cu" signal "L9GND")
		(20 "In9.Cu" signal "L10")
		(22 "In10.Cu" signal "L11GND")
		(24 "In11.Cu" signal "L12")
		(26 "In12.Cu" signal "L13GND")
		(2 "B.Cu" signal "BOTTOM")
		(9 "F.Adhes" user "F.Adhesive")
		(11 "B.Adhes" user "B.Adhesive")
		(13 "F.Paste" user "Package Geometry/Pastemask Top")
		(15 "B.Paste" user "Package Geometry/Pastemask Bottom")
		(5 "F.SilkS" user "Ref Des/Silkscreen Top")
		(7 "B.SilkS" user "Ref Des/Silkscreen Bottom")
		(1 "F.Mask" user "Board Geometry/Soldermask Top")
		(3 "B.Mask" user "Board Geometry/Soldermask Bottom")
		(17 "Dwgs.User" user "User.Drawings")
		(19 "Cmts.User" user "User.Comments")
		(21 "Eco1.User" user "User.Eco1")
		(23 "Eco2.User" user "User.Eco2")
		(25 "Edge.Cuts" user "Board Geometry/Outline")
		(27 "Margin" user)
		(31 "F.CrtYd" user "Package Geometry/Place Bound Top")
		(29 "B.CrtYd" user "Package Geometry/Place Bound Bottom")
		(35 "F.Fab" user "Ref Des/Assembly Top")
		(33 "B.Fab" user "Ref Des/Assembly Bottom")
	)
	(footprint ""
		(layer "F.Cu")
		(at 323.0245 -117.222016 90)
		(property "Reference" "C6B14"
			(at -0.8382 -0.67818 90)
			(unlocked yes)
			(layer "F.SilkS")
			(effects
				(font
					(size 0.4064 0.254)
					(thickness 0.1524)
				)
				(justify left)
			)
		)
		(property "Value" ""
			(at 0 0 90)
			(layer "F.Fab")
			(effects
				(font
					(size 1.27 1.27)
				)
			)
		)
		(duplicate_pad_numbers_are_jumpers no)
		(fp_poly
			(pts
				(xy 0.3048 -0.1016) (xy 0.3048 0.9906) (xy -0.3048 0.9906) (xy -0.3048 -0.1016)
			)
			(stroke
				(width 0)
				(type default)
			)
			(fill no)
			(layer "F.CrtYd")
		)
		(fp_line
			(start 0.3048 -0.1016)
			(end -0.3048 -0.1016)
			(stroke
				(width 0.1)
				(type default)
			)
			(layer "F.Fab")
		)
		(fp_line
			(start -0.3048 -0.1016)
			(end -0.3048 0.9906)
			(stroke
				(width 0.1)
				(type default)
			)
			(layer "F.Fab")
		)
		(fp_line
			(start 0.3048 0.9906)
			(end 0.3048 -0.1016)
			(stroke
				(width 0.1)
				(type default)
			)
			(layer "F.Fab")
		)
		(fp_line
			(start -0.3048 0.9906)
			(end 0.3048 0.9906)
			(stroke
				(width 0.1)
				(type default)
			)
			(layer "F.Fab")
		)
		(pad "1" smd rect
			(at 0 0 90)
			(size 0.508 0.508)
			(layers "F.Cu" "F.Mask" "F.Paste")
			(net "P3E_CPU0_PE1_PCH_TXN<11>")
		)
		(pad "2" smd rect
			(at 0 0.889 90)
			(size 0.508 0.508)
			(layers "F.Cu" "F.Mask" "F.Paste")
			(net "P3E_CPU0_PE1_PCH_C_TXN<11>")
		)
		(zone
			(layer "F.Cu")
			(hatch none 0.5)
			(connect_pads
				(clearance 0)
			)
			(min_thickness 0.25)
			(keepout
				(tracks allowed)
				(vias not_allowed)
				(pads allowed)
				(copperpour not_allowed)
				(footprints allowed)
			)
			(placement
				(enabled no)
				(sheetname "")
			)
			(fill
				(thermal_gap 0.5)
				(thermal_bridge_width 0.5)
				(island_removal_mode 0)
			)
			(polygon
				(pts
					(xy 323.2785 -116.968016) (xy 323.2785 -117.476016) (xy 323.6595 -117.476016) (xy 323.6595 -116.968016)
				)
			)
		)
		(zone
			(layer "F.Cu")
			(hatch none 0.5)
			(connect_pads
				(clearance 0)
			)
			(min_thickness 0.25)
			(keepout
				(tracks not_allowed)
				(vias allowed)
				(pads allowed)
				(copperpour not_allowed)
				(footprints allowed)
			)
			(placement
				(enabled no)
				(sheetname "")
			)
			(fill
				(thermal_gap 0.5)
				(thermal_bridge_width 0.5)
				(island_removal_mode 0)
			)
			(polygon
				(pts
					(xy 323.6595 -116.968016) (xy 323.6595 -117.476016) (xy 323.2785 -117.476016) (xy 323.2785 -116.968016)
				)
			)
		)
	)
	(footprint ""
		(layer "F.Cu")
		(at 27.451558 -22.952456)
		(property "Reference" "C1F19"
			(at 0 0 0)
			(layer "F.SilkS")
			(hide yes)
			(effects
				(font
					(size 1.27 1.27)
				)
			)
		)
		(property "Value" ""
			(at 0 0 0)
			(layer "F.Fab")
			(effects
				(font
					(size 1.27 1.27)
				)
			)
		)
		(duplicate_pad_numbers_are_jumpers no)
		(fp_poly
			(pts
				(xy 0.3048 -0.1016) (xy 0.3048 0.9906) (xy -0.3048 0.9906) (xy -0.3048 -0.1016)
			)
			(stroke
				(width 0)
				(type default)
			)
			(fill no)
			(layer "F.CrtYd")
		)
		(fp_line
			(start -0.3048 -0.1016)
			(end -0.3048 0.9906)
			(stroke
				(width 0.1)
				(type default)
			)
			(layer "F.Fab")
		)
		(fp_line
			(start -0.3048 0.9906)
			(end 0.3048 0.9906)
			(stroke
				(width 0.1)
				(type default)
			)
			(layer "F.Fab")
		)
		(fp_line
			(start 0.3048 -0.1016)
			(end -0.3048 -0.1016)
			(stroke
				(width 0.1)
				(type default)
			)
			(layer "F.Fab")
		)
		(fp_line
			(start 0.3048 0.9906)
			(end 0.3048 -0.1016)
			(stroke
				(width 0.1)
				(type default)
			)
			(layer "F.Fab")
		)
		(pad "1" smd rect
			(at 0 0)
			(size 0.508 0.508)
			(layers "F.Cu" "F.Mask" "F.Paste")
			(net "M_G_CPU_VREF")
		)
		(pad "2" smd rect
			(at 0 0.889)
			(size 0.508 0.508)
			(layers "F.Cu" "F.Mask" "F.Paste")
			(net "GND")
		)
		(zone
			(layer "F.Cu")
			(hatch none 0.5)
			(connect_pads
				(clearance 0)
			)
			(min_thickness 0.25)
			(keepout
				(tracks allowed)
				(vias not_allowed)
				(pads allowed)
				(copperpour not_allowed)
				(footprints allowed)
			)
			(placement
				(enabled no)
				(sheetname "")
			)
			(fill
				(thermal_gap 0.5)
				(thermal_bridge_width 0.5)
				(island_removal_mode 0)
			)
			(polygon
				(pts
					(xy 27.197558 -22.698456) (xy 27.705558 -22.698456) (xy 27.705558 -22.317456) (xy 27.197558 -22.317456)
				)
			)
		)
		(zone
			(layer "F.Cu")
			(hatch none 0.5)
			(connect_pads
				(clearance 0)
			)
			(min_thickness 0.25)
			(keepout
				(tracks not_allowed)
				(vias allowed)
				(pads allowed)
				(copperpour not_allowed)
				(footprints allowed)
			)
			(placement
				(enabled no)
				(sheetname "")
			)
			(fill
				(thermal_gap 0.5)
				(thermal_bridge_width 0.5)
				(island_removal_mode 0)
			)
			(polygon
				(pts
					(xy 27.197558 -22.317456) (xy 27.705558 -22.317456) (xy 27.705558 -22.698456) (xy 27.197558 -22.698456)
				)
			)
		)
	)
	(footprint ""
		(layer "F.Cu")
		(at 7.333234 4.307332)
		(property "Reference" "C1G24"
			(at 0 0 0)
			(layer "F.SilkS")
			(hide yes)
			(effects
				(font
					(size 1.27 1.27)
				)
			)
		)
		(property "Value" ""
			(at 0 0 0)
			(layer "F.Fab")
			(effects
				(font
					(size 1.27 1.27)
				)
			)
		)
		(duplicate_pad_numbers_are_jumpers no)
		(fp_rect
			(start -0.3048 -0.1016)
			(end 0.3048 0.9906)
			(stroke
				(width 0)
				(type default)
			)
			(fill no)
			(layer "F.CrtYd")
		)
		(fp_line
			(start -0.3048 -0.1016)
			(end -0.3048 0.9906)
			(stroke
				(width 0.1)
				(type default)
			)
			(layer "F.Fab")
		)
		(fp_line
			(start -0.3048 0.9906)
			(end 0.3048 0.9906)
			(stroke
				(width 0.1)
				(type default)
			)
			(layer "F.Fab")
		)
		(fp_line
			(start 0.3048 -0.1016)
			(end -0.3048 -0.1016)
			(stroke
				(width 0.1)
				(type default)
			)
			(layer "F.Fab")
		)
		(fp_line
			(start 0.3048 0.9906)
			(end 0.3048 -0.1016)
			(stroke
				(width 0.1)
				(type default)
			)
			(layer "F.Fab")
		)
		(pad "1" smd rect
			(at 0 0)
			(size 0.508 0.508)
			(layers "F.Cu" "F.Mask" "F.Paste")
			(net "A_TSENSE_PVDDQ_GHJ")
		)
		(pad "2" smd rect
			(at 0 0.889)
			(size 0.508 0.508)
			(layers "F.Cu" "F.Mask" "F.Paste")
			(net "GND")
		)
		(zone
			(layer "F.Cu")
			(hatch none 0.5)
			(connect_pads
				(clearance 0)
			)
			(min_thickness 0.25)
			(keepout
				(tracks allowed)
				(vias not_allowed)
				(pads allowed)
				(copperpour not_allowed)
				(footprints allowed)
			)
			(placement
				(enabled no)
				(sheetname "")
			)
			(fill
				(thermal_gap 0.5)
				(thermal_bridge_width 0.5)
				(island_removal_mode 0)
			)
			(polygon
				(pts
					(xy 7.079234 4.561332) (xy 7.079234 4.942332) (xy 7.587234 4.942332) (xy 7.587234 4.561332)
				)
			)
		)
		(zone
			(layer "F.Cu")
			(hatch none 0.5)
			(connect_pads
				(clearance 0)
			)
			(min_thickness 0.25)
			(keepout
				(tracks not_allowed)
				(vias allowed)
				(pads allowed)
				(copperpour not_allowed)
				(footprints allowed)
			)
			(placement
				(enabled no)
				(sheetname "")
			)
			(fill
				(thermal_gap 0.5)
				(thermal_bridge_width 0.5)
				(island_removal_mode 0)
			)
			(polygon
				(pts
					(xy 7.079234 4.561332) (xy 7.079234 4.942332) (xy 7.587234 4.942332) (xy 7.587234 4.561332)
				)
			)
		)
	)
	(footprint ""
		(layer "F.Cu")
		(at 172.466 -131.5085)
		(property "Reference" "C4B5"
			(at 0 0 0)
			(layer "F.SilkS")
			(hide yes)
			(effects
				(font
					(size 1.27 1.27)
				)
			)
		)
		(property "Value" ""
			(at 0 0 0)
			(layer "F.Fab")
			(effects
				(font
					(size 1.27 1.27)
				)
			)
		)
		(duplicate_pad_numbers_are_jumpers no)
		(fp_poly
			(pts
				(xy 0.3048 -0.1016) (xy 0.3048 0.9906) (xy -0.3048 0.9906) (xy -0.3048 -0.1016)
			)
			(stroke
				(width 0)
				(type default)
			)
			(fill no)
			(layer "F.CrtYd")
		)
		(fp_line
			(start -0.3048 -0.1016)
			(end -0.3048 0.9906)
			(stroke
				(width 0.1)
				(type default)
			)
			(layer "F.Fab")
		)
		(fp_line
			(start -0.3048 0.9906)
			(end 0.3048 0.9906)
			(stroke
				(width 0.1)
				(type default)
			)
			(layer "F.Fab")
		)
		(fp_line
			(start 0.3048 -0.1016)
			(end -0.3048 -0.1016)
			(stroke
				(width 0.1)
				(type default)
			)
			(layer "F.Fab")
		)
		(fp_line
			(start 0.3048 0.9906)
			(end 0.3048 -0.1016)
			(stroke
				(width 0.1)
				(type default)
			)
			(layer "F.Fab")
		)
		(pad "1" smd rect
			(at 0 0)
			(size 0.508 0.508)
			(layers "F.Cu" "F.Mask" "F.Paste")
			(net "FM_PVPP_CPU1_EN")
		)
		(pad "2" smd rect
			(at 0 0.889)
			(size 0.508 0.508)
			(layers "F.Cu" "F.Mask" "F.Paste")
			(net "AGND_PVPP_KLM")
		)
		(zone
			(layer "F.Cu")
			(hatch none 0.5)
			(connect_pads
				(clearance 0)
			)
			(min_thickness 0.25)
			(keepout
				(tracks allowed)
				(vias not_allowed)
				(pads allowed)
				(copperpour not_allowed)
				(footprints allowed)
			)
			(placement
				(enabled no)
				(sheetname "")
			)
			(fill
				(thermal_gap 0.5)
				(thermal_bridge_width 0.5)
				(island_removal_mode 0)
			)
			(polygon
				(pts
					(xy 172.212 -131.2545) (xy 172.72 -131.2545) (xy 172.72 -130.8735) (xy 172.212 -130.8735)
				)
			)
		)
		(zone
			(layer "F.Cu")
			(hatch none 0.5)
			(connect_pads
				(clearance 0)
			)
			(min_thickness 0.25)
			(keepout
				(tracks not_allowed)
				(vias allowed)
				(pads allowed)
				(copperpour not_allowed)
				(footprints allowed)
			)
			(placement
				(enabled no)
				(sheetname "")
			)
			(fill
				(thermal_gap 0.5)
				(thermal_bridge_width 0.5)
				(island_removal_mode 0)
			)
			(polygon
				(pts
					(xy 172.212 -130.8735) (xy 172.72 -130.8735) (xy 172.72 -131.2545) (xy 172.212 -131.2545)
				)
			)
		)
	)
	(footprint ""
		(layer "F.Cu")
		(at 264.4394 -79.6036 180)
		(property "Reference" "C5D16"
			(at 0 0 180)
			(layer "F.SilkS")
			(hide yes)
			(effects
				(font
					(size 1.27 1.27)
				)
			)
		)
		(property "Value" ""
			(at 0 0 180)
			(layer "F.Fab")
			(effects
				(font
					(size 1.27 1.27)
				)
			)
		)
		(duplicate_pad_numbers_are_jumpers no)
		(fp_poly
			(pts
				(xy -0.4953 -0.2032) (xy 0.4953 -0.2032) (xy 0.4953 1.6002) (xy -0.4953 1.6002)
			)
			(stroke
				(width 0)
				(type default)
			)
			(fill no)
			(layer "F.CrtYd")
		)
		(fp_line
			(start 0.4953 1.6002)
			(end -0.4953 1.6002)
			(stroke
				(width 0.1)
				(type default)
			)
			(layer "F.Fab")
		)
		(fp_line
			(start 0.4953 -0.2032)
			(end 0.4953 1.6002)
			(stroke
				(width 0.1)
				(type default)
			)
			(layer "F.Fab")
		)
		(fp_line
			(start -0.4953 1.6002)
			(end -0.4953 -0.2032)
			(stroke
				(width 0.1)
				(type default)
			)
			(layer "F.Fab")
		)
		(fp_line
			(start -0.4953 -0.2032)
			(end 0.4953 -0.2032)
			(stroke
				(width 0.1)
				(type default)
			)
			(layer "F.Fab")
		)
		(pad "1" smd rect
			(at 0 0 180)
			(size 0.762 0.889)
			(layers "F.Cu" "F.Mask" "F.Paste")
			(net "PVCCIN_CPU0")
		)
		(pad "2" smd rect
			(at 0 1.397 180)
			(size 0.762 0.889)
			(layers "F.Cu" "F.Mask" "F.Paste")
			(net "GND")
		)
		(zone
			(layer "F.Cu")
			(hatch none 0.5)
			(connect_pads
				(clearance 0)
			)
			(min_thickness 0.25)
			(keepout
				(tracks not_allowed)
				(vias allowed)
				(pads allowed)
				(copperpour not_allowed)
				(footprints allowed)
			)
			(placement
				(enabled no)
				(sheetname "")
			)
			(fill
				(thermal_gap 0.5)
				(thermal_bridge_width 0.5)
				(island_removal_mode 0)
			)
			(polygon
				(pts
					(xy 264.8204 -80.0481) (xy 264.0584 -80.0481) (xy 264.0584 -80.5561) (xy 264.8204 -80.5561)
				)
			)
		)
	)
	(footprint ""
		(layer "F.Cu")
		(at 426.5295 -128.1557 -90)
		(property "Reference" "R8B8"
			(at 0 0 270)
			(layer "F.SilkS")
			(hide yes)
			(effects
				(font
					(size 1.27 1.27)
				)
			)
		)
		(property "Value" ""
			(at 0 0 270)
			(layer "F.Fab")
			(effects
				(font
					(size 1.27 1.27)
				)
			)
		)
		(duplicate_pad_numbers_are_jumpers no)
		(fp_poly
			(pts
				(xy -0.2794 -0.1016) (xy 0.2794 -0.1016) (xy 0.2794 0.9906) (xy -0.2794 0.9906)
			)
			(stroke
				(width 0)
				(type default)
			)
			(fill no)
			(layer "F.CrtYd")
		)
		(fp_line
			(start -0.2794 0.9906)
			(end 0.2794 0.9906)
			(stroke
				(width 0.1)
				(type default)
			)
			(layer "F.Fab")
		)
		(fp_line
			(start 0.2794 0.9906)
			(end 0.2794 -0.1016)
			(stroke
				(width 0.1)
				(type default)
			)
			(layer "F.Fab")
		)
		(fp_line
			(start -0.2794 -0.1016)
			(end -0.2794 0.9906)
			(stroke
				(width 0.1)
				(type default)
			)
			(layer "F.Fab")
		)
		(fp_line
			(start 0.2794 -0.1016)
			(end -0.2794 -0.1016)
			(stroke
				(width 0.1)
				(type default)
			)
			(layer "F.Fab")
		)
		(pad "1" smd rect
			(at 0 0 270)
			(size 0.508 0.508)
			(layers "F.Cu" "F.Mask" "F.Paste")
			(net "PVPP_ABC")
		)
		(pad "2" smd rect
			(at 0 0.889 270)
			(size 0.508 0.508)
			(layers "F.Cu" "F.Mask" "F.Paste")
			(net "RST_HFI0_CPU0_LVT2_N")
		)
		(zone
			(layer "F.Cu")
			(hatch none 0.5)
			(connect_pads
				(clearance 0)
			)
			(min_thickness 0.25)
			(keepout
				(tracks not_allowed)
				(vias allowed)
				(pads allowed)
				(copperpour not_allowed)
				(footprints allowed)
			)
			(placement
				(enabled no)
				(sheetname "")
			)
			(fill
				(thermal_gap 0.5)
				(thermal_bridge_width 0.5)
				(island_removal_mode 0)
			)
			(polygon
				(pts
					(xy 425.8945 -128.4097) (xy 425.8945 -127.9017) (xy 426.2755 -127.9017) (xy 426.2755 -128.4097)
				)
			)
		)
		(zone
			(layer "F.Cu")
			(hatch none 0.5)
			(connect_pads
				(clearance 0)
			)
			(min_thickness 0.25)
			(keepout
				(tracks allowed)
				(vias not_allowed)
				(pads allowed)
				(copperpour not_allowed)
				(footprints allowed)
			)
			(placement
				(enabled no)
				(sheetname "")
			)
			(fill
				(thermal_gap 0.5)
				(thermal_bridge_width 0.5)
				(island_removal_mode 0)
			)
			(polygon
				(pts
					(xy 426.2755 -128.4097) (xy 426.2755 -127.9017) (xy 425.8945 -127.9017) (xy 425.8945 -128.4097)
				)
			)
		)
	)
)
